# S9S_MB_2U (Grand Teton) — schematic netlist excerpt (pin names and nets, part order shuffled) for the footprints in the layout excerpt that follows; sources: Cadence DE-HDL packaged netlist, KiCad conversion of 03242023_DA0F0TMBIJ0_F0T_Motherboard_J_brd_V01_OCP.brd

PC638  Q_CAP  22UF 16V 20% X6S  pkg C0805  page 279 : A = SW_P12V_PVCCINFAON_CPU0_FLT ; B = GND
R1302  Q_RES  2K 1% EMPTY  pkg 0402LF  page 219 : A = PWRGD_DRAMPWRGD_CPU0_AB_R_LVC1 ; B = GND

(kicad_pcb
	(version 20260206)
	(generator "pcbnew")
	(generator_version "10.0")
	(general
		(thickness 1.6)
		(legacy_teardrops no)
	)
	(paper "A4")
	(title_block
		(title "03242023_DA0F0TMBIJ0_F0T_Motherboard_J_brd_V01_OCP.brd")
		(comment 1 "Grand Teton / footprints 4759-4760 of 6105")
	)
	(layers
		(0 "F.Cu" signal "TOP")
		(4 "In1.Cu" signal "GND")
		(6 "In2.Cu" signal "IN1")
		(8 "In3.Cu" signal "GND1")
		(10 "In4.Cu" signal "IN2")
		(12 "In5.Cu" signal "GND2")
		(14 "In6.Cu" signal "IN3")
		(16 "In7.Cu" signal "GND3")
		(18 "In8.Cu" signal "VCC")
		(20 "In9.Cu" signal "VCC1")
		(22 "In10.Cu" signal "GND4")
		(24 "In11.Cu" signal "IN4")
		(26 "In12.Cu" signal "GND5")
		(28 "In13.Cu" signal "IN5")
		(30 "In14.Cu" signal "GND6")
		(32 "In15.Cu" signal "IN6")
		(34 "In16.Cu" signal "GND7")
		(2 "B.Cu" signal "BOTTOM")
		(9 "F.Adhes" user "F.Adhesive")
		(11 "B.Adhes" user "B.Adhesive")
		(13 "F.Paste" user "Package Geometry/Pastemask Top")
		(15 "B.Paste" user "Package Geometry/Pastemask Bottom")
		(5 "F.SilkS" user "Ref Des/Silkscreen Top")
		(7 "B.SilkS" user "Ref Des/Silkscreen Bottom")
		(1 "F.Mask" user "Board Geometry/Soldermask Top")
		(3 "B.Mask" user "Board Geometry/Soldermask Bottom")
		(17 "Dwgs.User" user "User.Drawings")
		(19 "Cmts.User" user "User.Comments")
		(21 "Eco1.User" user "User.Eco1")
		(23 "Eco2.User" user "User.Eco2")
		(25 "Edge.Cuts" user "Board Geometry/Outline")
		(27 "Margin" user)
		(31 "F.CrtYd" user "Package Geometry/Place Bound Top")
		(29 "B.CrtYd" user "Package Geometry/Place Bound Bottom")
		(35 "F.Fab" user "Ref Des/Assembly Top")
		(33 "B.Fab" user "Ref Des/Assembly Bottom")
	)
	(footprint ""
		(layer "B.Cu")
		(at 416.02914 -161.064194)
		(property "Reference" "PC638"
			(at 0 0 0)
			(layer "B.SilkS")
			(hide yes)
			(effects
				(font
					(size 1.27 1.27)
				)
				(justify mirror)
			)
		)
		(property "Value" ""
			(at 0 0 0)
			(layer "B.Fab")
			(effects
				(font
					(size 1.27 1.27)
				)
				(justify mirror)
			)
		)
		(duplicate_pad_numbers_are_jumpers no)
		(fp_line
			(start -1.524 -0.762)
			(end -1.524 0.762)
			(stroke
				(width 0.1524)
				(type default)
			)
			(layer "B.SilkS")
		)
		(fp_line
			(start -1.524 0.762)
			(end 1.524 0.762)
			(stroke
				(width 0.1524)
				(type default)
			)
			(layer "B.SilkS")
		)
		(fp_line
			(start 1.524 -0.762)
			(end -1.524 -0.762)
			(stroke
				(width 0.1524)
				(type default)
			)
			(layer "B.SilkS")
		)
		(fp_line
			(start 1.524 0.762)
			(end 1.524 -0.762)
			(stroke
				(width 0.1524)
				(type default)
			)
			(layer "B.SilkS")
		)
		(fp_line
			(start -1.1049 -0.724916)
			(end 1.1049 -0.724916)
			(stroke
				(width 0.1)
				(type default)
			)
			(layer "B.Fab")
		)
		(fp_line
			(start -1.1049 0.724916)
			(end -1.1049 -0.724916)
			(stroke
				(width 0.1)
				(type default)
			)
			(layer "B.Fab")
		)
		(fp_line
			(start 1.1049 -0.724916)
			(end 1.1049 0.724916)
			(stroke
				(width 0.1)
				(type default)
			)
			(layer "B.Fab")
		)
		(fp_line
			(start 1.1049 0.724916)
			(end -1.1049 0.724916)
			(stroke
				(width 0.1)
				(type default)
			)
			(layer "B.Fab")
		)
		(pad "1" smd rect
			(at 0.889 0)
			(size 1.016 1.27)
			(layers "B.Cu" "B.Mask" "B.Paste")
			(net "SW_P12V_PVCCINFAON_CPU0_FLT")
		)
		(pad "2" smd rect
			(at -0.889 0)
			(size 1.016 1.27)
			(layers "B.Cu" "B.Mask" "B.Paste")
			(net "GND")
		)
	)
	(footprint ""
		(layer "B.Cu")
		(at 178.120802 -104.71277 180)
		(property "Reference" "R1302"
			(at 0 0 0)
			(layer "B.SilkS")
			(hide yes)
			(effects
				(font
					(size 1.27 1.27)
				)
				(justify mirror)
			)
		)
		(property "Value" ""
			(at 0 0 0)
			(layer "B.Fab")
			(effects
				(font
					(size 1.27 1.27)
				)
				(justify mirror)
			)
		)
		(duplicate_pad_numbers_are_jumpers no)
		(fp_line
			(start 0.7874 0.4064)
			(end 0.7874 -0.4064)
			(stroke
				(width 0.1524)
				(type default)
			)
			(layer "B.SilkS")
		)
		(fp_line
			(start 0.7874 -0.4064)
			(end -0.7874 -0.4064)
			(stroke
				(width 0.1524)
				(type default)
			)
			(layer "B.SilkS")
		)
		(fp_line
			(start -0.7874 0.4064)
			(end 0.7874 0.4064)
			(stroke
				(width 0.1524)
				(type default)
			)
			(layer "B.SilkS")
		)
		(fp_line
			(start -0.7874 -0.4064)
			(end -0.7874 0.4064)
			(stroke
				(width 0.1524)
				(type default)
			)
			(layer "B.SilkS")
		)
		(fp_line
			(start 0.67945 0.3048)
			(end 0.67945 -0.305054)
			(stroke
				(width 0.1)
				(type default)
			)
			(layer "B.Fab")
		)
		(fp_line
			(start 0.67945 -0.305054)
			(end 0.12065 -0.305054)
			(stroke
				(width 0.1)
				(type default)
			)
			(layer "B.Fab")
		)
		(fp_line
			(start 0.12065 0.3048)
			(end 0.67945 0.3048)
			(stroke
				(width 0.1)
				(type default)
			)
			(layer "B.Fab")
		)
		(fp_line
			(start 0.12065 0.2794)
			(end 0.12065 0.3048)
			(stroke
				(width 0.1)
				(type default)
			)
			(layer "B.Fab")
		)
		(fp_line
			(start 0.12065 -0.2794)
			(end -0.12065 -0.2794)
			(stroke
				(width 0.1)
				(type default)
			)
			(layer "B.Fab")
		)
		(fp_line
			(start 0.12065 -0.305054)
			(end 0.12065 -0.2794)
			(stroke
				(width 0.1)
				(type default)
			)
			(layer "B.Fab")
		)
		(fp_line
			(start -0.120396 0.3048)
			(end -0.120396 0.2794)
			(stroke
				(width 0.1)
				(type default)
			)
			(layer "B.Fab")
		)
		(fp_line
			(start -0.120396 0.2794)
			(end 0.12065 0.2794)
			(stroke
				(width 0.1)
				(type default)
			)
			(layer "B.Fab")
		)
		(fp_line
			(start -0.12065 -0.2794)
			(end -0.12065 -0.3048)
			(stroke
				(width 0.1)
				(type default)
			)
			(layer "B.Fab")
		)
		(fp_line
			(start -0.12065 -0.3048)
			(end -0.67945 -0.3048)
			(stroke
				(width 0.1)
				(type default)
			)
			(layer "B.Fab")
		)
		(fp_line
			(start -0.67945 0.3048)
			(end -0.120396 0.3048)
			(stroke
				(width 0.1)
				(type default)
			)
			(layer "B.Fab")
		)
		(fp_line
			(start -0.67945 -0.3048)
			(end -0.67945 0.3048)
			(stroke
				(width 0.1)
				(type default)
			)
			(layer "B.Fab")
		)
		(pad "1" smd circle
			(at 0.40005 0)
			(size 0 0)
			(layers "B.Cu" "B.Mask" "B.Paste")
			(net "PWRGD_DRAMPWRGD_CPU0_AB_R_LVC1")
		)
		(pad "2" smd circle
			(at -0.40005 0)
			(size 0 0)
			(layers "B.Cu" "B.Mask" "B.Paste")
			(net "GND")
		)
	)
)
